(kicad_pcb
	(version 20260206)
	(generator "pcbnew")
	(generator_version "10.0")
	(general
		(thickness 1.6)
		(legacy_teardrops no)
	)
	(paper "A4")
	(title_block
		(title "timecard-production-celestica-r4006 — R4006-B0001-02_R01.brd")
		(comment 1 "Time Appliance Project (Time Card) / footprints 259-263 of 1113")
	)
	(layers
		(0 "F.Cu" signal "TOP")
		(4 "In1.Cu" signal "L02_GND1")
		(6 "In2.Cu" signal "L03_SIG1")
		(8 "In3.Cu" signal "L04_GND2")
		(10 "In4.Cu" signal "L05_VCC1")
		(12 "In5.Cu" signal "L06_VCC2")
		(14 "In6.Cu" signal "L07_GND3")
		(16 "In7.Cu" signal "L08_SIG2")
		(18 "In8.Cu" signal "L09_GND4")
		(2 "B.Cu" signal "BOTTOM")
		(9 "F.Adhes" user "F.Adhesive")
		(11 "B.Adhes" user "B.Adhesive")
		(13 "F.Paste" user "Package Geometry/Pastemask Top")
		(15 "B.Paste" user "Package Geometry/Pastemask Bottom")
		(5 "F.SilkS" user "Ref Des/Silkscreen Top")
		(7 "B.SilkS" user "Ref Des/Silkscreen Bottom")
		(1 "F.Mask" user "Board Geometry/Soldermask Top")
		(3 "B.Mask" user "Board Geometry/Soldermask Bottom")
		(17 "Dwgs.User" user "User.Drawings")
		(19 "Cmts.User" user "User.Comments")
		(21 "Eco1.User" user "User.Eco1")
		(23 "Eco2.User" user "User.Eco2")
		(25 "Edge.Cuts" user "Board Geometry/Outline")
		(27 "Margin" user)
		(31 "F.CrtYd" user "Package Geometry/Place Bound Top")
		(29 "B.CrtYd" user "Package Geometry/Place Bound Bottom")
		(35 "F.Fab" user "Ref Des/Assembly Top")
		(33 "B.Fab" user "Ref Des/Assembly Bottom")
	)
	(footprint ""
		(layer "F.Cu")
		(at 38.227 -74.93 180)
		(property "Reference" "R489"
			(at -0.508 -1.30937 0)
			(unlocked yes)
			(layer "F.SilkS")
			(effects
				(font
					(size 0.7874 0.5842)
					(thickness 0.1524)
				)
			)
		)
		(property "Value" "VAL*"
			(at 0.0508 2.245106 180)
			(unlocked yes)
			(layer "F.Fab")
			(hide yes)
			(effects
				(font
					(size 0.7874 0.5842)
					(thickness 0.1524)
				)
			)
		)
		(property "User Part Number" "PARTNUM*"
			(at 0.0762 4.302506 180)
			(unlocked yes)
			(layer "Cmts.User")
			(hide yes)
			(effects
				(font
					(size 0.7874 0.5842)
					(thickness 0.1524)
				)
			)
		)
		(property "Device Type" "RESISTOR-G155-03921-01,3.92KOHA"
			(at 0.0762 1.254506 180)
			(unlocked yes)
			(layer "F.Fab")
			(hide yes)
			(effects
				(font
					(size 0.7874 0.5842)
					(thickness 0.1524)
				)
			)
		)
		(property "Tolerance" "TOL*"
			(at 0.0508 3.261106 180)
			(unlocked yes)
			(layer "Cmts.User")
			(hide yes)
			(effects
				(font
					(size 0.7874 0.5842)
					(thickness 0.1524)
				)
			)
		)
		(duplicate_pad_numbers_are_jumpers no)
		(fp_line
			(start 1.143 0.5588)
			(end 1.143 -0.5588)
			(stroke
				(width 0.1)
				(type default)
			)
			(layer "F.SilkS")
		)
		(fp_line
			(start 1.143 -0.5588)
			(end -1.143 -0.5588)
			(stroke
				(width 0.1)
				(type default)
			)
			(layer "F.SilkS")
		)
		(fp_line
			(start -1.143 0.5588)
			(end 1.143 0.5588)
			(stroke
				(width 0.1)
				(type default)
			)
			(layer "F.SilkS")
		)
		(fp_line
			(start -1.143 -0.5588)
			(end -1.143 0.5588)
			(stroke
				(width 0.1)
				(type default)
			)
			(layer "F.SilkS")
		)
		(fp_poly
			(pts
				(xy -1.143 0.5588) (xy 1.143 0.5588) (xy 1.143 -0.5588) (xy -1.143 -0.5588)
			)
			(stroke
				(width 0)
				(type default)
			)
			(fill no)
			(layer "F.CrtYd")
		)
		(fp_line
			(start 0.508 0.3048)
			(end 0.508 -0.3048)
			(stroke
				(width 0.1)
				(type default)
			)
			(layer "F.Fab")
		)
		(fp_line
			(start 0.508 -0.3048)
			(end -0.508 -0.3048)
			(stroke
				(width 0.1)
				(type default)
			)
			(layer "F.Fab")
		)
		(fp_line
			(start -0.508 0.3048)
			(end 0.508 0.3048)
			(stroke
				(width 0.1)
				(type default)
			)
			(layer "F.Fab")
		)
		(fp_line
			(start -0.508 -0.3048)
			(end -0.508 0.3048)
			(stroke
				(width 0.1)
				(type default)
			)
			(layer "F.Fab")
		)
		(pad "1" smd rect
			(at -0.5334 0 180)
			(size 0.7112 0.6096)
			(layers "F.Cu" "F.Mask" "F.Paste")
			(net "UNNAMED_525_ISL80101IRAJZDFN10_")
		)
		(pad "2" smd rect
			(at 0.5334 0 180)
			(size 0.7112 0.6096)
			(layers "F.Cu" "F.Mask" "F.Paste")
			(net "SG")
		)
		(zone
			(layer "F.Cu")
			(hatch none 0.5)
			(connect_pads
				(clearance 0)
			)
			(min_thickness 0.25)
			(keepout
				(tracks allowed)
				(vias not_allowed)
				(pads allowed)
				(copperpour not_allowed)
				(footprints allowed)
			)
			(placement
				(enabled no)
				(sheetname "")
			)
			(fill
				(thermal_gap 0.5)
				(thermal_bridge_width 0.5)
				(island_removal_mode 0)
			)
			(polygon
				(pts
					(xy 38.3032 -75.2348) (xy 38.1508 -75.2348) (xy 38.1508 -74.6252) (xy 38.3032 -74.6252)
				)
			)
		)
		(zone
			(layer "F.Cu")
			(hatch none 0.5)
			(connect_pads
				(clearance 0)
			)
			(min_thickness 0.25)
			(keepout
				(tracks not_allowed)
				(vias allowed)
				(pads allowed)
				(copperpour not_allowed)
				(footprints allowed)
			)
			(placement
				(enabled no)
				(sheetname "")
			)
			(fill
				(thermal_gap 0.5)
				(thermal_bridge_width 0.5)
				(island_removal_mode 0)
			)
			(polygon
				(pts
					(xy 38.3032 -75.2348) (xy 38.1508 -75.2348) (xy 38.1508 -74.6252) (xy 38.3032 -74.6252)
				)
			)
		)
	)
	(footprint ""
		(layer "F.Cu")
		(at 16.852392 -67.6656)
		(property "Reference" "R72"
			(at -1.993392 -0.50165 0)
			(unlocked yes)
			(layer "F.SilkS")
			(effects
				(font
					(size 0.635 0.4064)
					(thickness 0.1524)
				)
			)
		)
		(property "Value" "VAL*"
			(at 0.02032 2.13233 0)
			(unlocked yes)
			(layer "F.Fab")
			(hide yes)
			(effects
				(font
					(size 0.7874 0.5842)
					(thickness 0.1524)
				)
			)
		)
		(property "Tolerance" "TOL*"
			(at 0.044704 3.05435 0)
			(unlocked yes)
			(layer "Cmts.User")
			(hide yes)
			(effects
				(font
					(size 0.7874 0.5842)
					(thickness 0.1524)
				)
			)
		)
		(property "User Part Number" "PARTNUM*"
			(at 0.02032 4.024884 0)
			(unlocked yes)
			(layer "Cmts.User")
			(hide yes)
			(effects
				(font
					(size 0.7874 0.5842)
					(thickness 0.1524)
				)
			)
		)
		(property "Device Type" "RESISTOR-G155-133R0-01,33OHM,1%"
			(at 0.008382 1.210564 0)
			(unlocked yes)
			(layer "F.Fab")
			(hide yes)
			(effects
				(font
					(size 0.7874 0.5842)
					(thickness 0.1524)
				)
			)
		)
		(duplicate_pad_numbers_are_jumpers no)
		(fp_line
			(start -1.143 -0.5588)
			(end -1.143 0.5588)
			(stroke
				(width 0.1)
				(type default)
			)
			(layer "F.SilkS")
		)
		(fp_line
			(start -1.143 0.5588)
			(end 1.143 0.5588)
			(stroke
				(width 0.1)
				(type default)
			)
			(layer "F.SilkS")
		)
		(fp_line
			(start 1.143 -0.5588)
			(end -1.143 -0.5588)
			(stroke
				(width 0.1)
				(type default)
			)
			(layer "F.SilkS")
		)
		(fp_line
			(start 1.143 0.5588)
			(end 1.143 -0.5588)
			(stroke
				(width 0.1)
				(type default)
			)
			(layer "F.SilkS")
		)
		(fp_rect
			(start -1.143 -0.5588)
			(end 1.143 0.5588)
			(stroke
				(width 0)
				(type default)
			)
			(fill no)
			(layer "F.CrtYd")
		)
		(fp_line
			(start -0.508 -0.3048)
			(end -0.508 0.3048)
			(stroke
				(width 0.1)
				(type default)
			)
			(layer "F.Fab")
		)
		(fp_line
			(start -0.508 0.3048)
			(end 0.508 0.3048)
			(stroke
				(width 0.1)
				(type default)
			)
			(layer "F.Fab")
		)
		(fp_line
			(start 0.508 -0.3048)
			(end -0.508 -0.3048)
			(stroke
				(width 0.1)
				(type default)
			)
			(layer "F.Fab")
		)
		(fp_line
			(start 0.508 0.3048)
			(end 0.508 -0.3048)
			(stroke
				(width 0.1)
				(type default)
			)
			(layer "F.Fab")
		)
		(pad "1" smd rect
			(at -0.5334 0)
			(size 0.7112 0.6096)
			(layers "F.Cu" "F.Mask" "F.Paste")
			(net "BF_ICP10100_I2C_SDA")
		)
		(pad "2" smd rect
			(at 0.5334 0)
			(size 0.7112 0.6096)
			(layers "F.Cu" "F.Mask" "F.Paste")
			(net "R_ICP10100_I2C_SDA")
		)
		(zone
			(layer "F.Cu")
			(hatch none 0.5)
			(connect_pads
				(clearance 0)
			)
			(min_thickness 0.25)
			(keepout
				(tracks allowed)
				(vias not_allowed)
				(pads allowed)
				(copperpour not_allowed)
				(footprints allowed)
			)
			(placement
				(enabled no)
				(sheetname "")
			)
			(fill
				(thermal_gap 0.5)
				(thermal_bridge_width 0.5)
				(island_removal_mode 0)
			)
			(polygon
				(pts
					(xy 16.776192 -67.9704) (xy 16.776192 -67.3608) (xy 16.928592 -67.3608) (xy 16.928592 -67.9704)
				)
			)
		)
	)
	(footprint ""
		(layer "F.Cu")
		(at 46.863 -77.216)
		(property "Reference" "C304"
			(at 3.175 0.16637 0)
			(unlocked yes)
			(layer "F.SilkS")
			(effects
				(font
					(size 0.7874 0.5842)
					(thickness 0.1524)
				)
			)
		)
		(property "Value" "VAL*"
			(at 0.0762 2.067306 0)
			(unlocked yes)
			(layer "F.Fab")
			(hide yes)
			(effects
				(font
					(size 0.7874 0.5842)
					(thickness 0.1524)
				)
			)
		)
		(property "Tolerance" "TOL*"
			(at 0.0762 3.032506 0)
			(unlocked yes)
			(layer "Cmts.User")
			(hide yes)
			(effects
				(font
					(size 0.7874 0.5842)
					(thickness 0.1524)
				)
			)
		)
		(property "User Part Number" "PARTNUM*"
			(at 0.1016 4.023106 0)
			(unlocked yes)
			(layer "Cmts.User")
			(hide yes)
			(effects
				(font
					(size 0.7874 0.5842)
					(thickness 0.1524)
				)
			)
		)
		(property "Device Type" "CAPACITOR-G105-0B104-EK,0.1UF,A"
			(at 0.0508 1.127506 0)
			(unlocked yes)
			(layer "F.Fab")
			(hide yes)
			(effects
				(font
					(size 0.7874 0.5842)
					(thickness 0.1524)
				)
			)
		)
		(duplicate_pad_numbers_are_jumpers no)
		(fp_line
			(start -1.143 -0.5588)
			(end -1.143 0.5588)
			(stroke
				(width 0.1)
				(type default)
			)
			(layer "F.SilkS")
		)
		(fp_line
			(start -1.143 0.5588)
			(end 1.143 0.5588)
			(stroke
				(width 0.1)
				(type default)
			)
			(layer "F.SilkS")
		)
		(fp_line
			(start 1.143 -0.5588)
			(end -1.143 -0.5588)
			(stroke
				(width 0.1)
				(type default)
			)
			(layer "F.SilkS")
		)
		(fp_line
			(start 1.143 0.5588)
			(end 1.143 -0.5588)
			(stroke
				(width 0.1)
				(type default)
			)
			(layer "F.SilkS")
		)
		(fp_poly
			(pts
				(xy -1.143 0.5588) (xy 1.143 0.5588) (xy 1.143 -0.5588) (xy -1.143 -0.5588)
			)
			(stroke
				(width 0)
				(type default)
			)
			(fill no)
			(layer "F.CrtYd")
		)
		(fp_line
			(start -0.508 -0.3048)
			(end -0.508 0.3048)
			(stroke
				(width 0.1)
				(type default)
			)
			(layer "F.Fab")
		)
		(fp_line
			(start -0.508 0.3048)
			(end 0.508 0.3048)
			(stroke
				(width 0.1)
				(type default)
			)
			(layer "F.Fab")
		)
		(fp_line
			(start 0.508 -0.3048)
			(end -0.508 -0.3048)
			(stroke
				(width 0.1)
				(type default)
			)
			(layer "F.Fab")
		)
		(fp_line
			(start 0.508 0.3048)
			(end 0.508 -0.3048)
			(stroke
				(width 0.1)
				(type default)
			)
			(layer "F.Fab")
		)
		(pad "1" smd rect
			(at -0.5334 0)
			(size 0.7112 0.6096)
			(layers "F.Cu" "F.Mask" "F.Paste")
			(net "UNNAMED_525_CAPACITOR_I16_1")
		)
		(pad "2" smd rect
			(at 0.5334 0)
			(size 0.7112 0.6096)
			(layers "F.Cu" "F.Mask" "F.Paste")
			(net "SG")
		)
		(zone
			(layer "F.Cu")
			(hatch none 0.5)
			(connect_pads
				(clearance 0)
			)
			(min_thickness 0.25)
			(keepout
				(tracks not_allowed)
				(vias allowed)
				(pads allowed)
				(copperpour not_allowed)
				(footprints allowed)
			)
			(placement
				(enabled no)
				(sheetname "")
			)
			(fill
				(thermal_gap 0.5)
				(thermal_bridge_width 0.5)
				(island_removal_mode 0)
			)
			(polygon
				(pts
					(xy 46.7868 -76.9112) (xy 46.9392 -76.9112) (xy 46.9392 -77.5208) (xy 46.7868 -77.5208)
				)
			)
		)
		(zone
			(layer "F.Cu")
			(hatch none 0.5)
			(connect_pads
				(clearance 0)
			)
			(min_thickness 0.25)
			(keepout
				(tracks allowed)
				(vias not_allowed)
				(pads allowed)
				(copperpour not_allowed)
				(footprints allowed)
			)
			(placement
				(enabled no)
				(sheetname "")
			)
			(fill
				(thermal_gap 0.5)
				(thermal_bridge_width 0.5)
				(island_removal_mode 0)
			)
			(polygon
				(pts
					(xy 46.7868 -76.9112) (xy 46.9392 -76.9112) (xy 46.9392 -77.5208) (xy 46.7868 -77.5208)
				)
			)
		)
	)
	(footprint ""
		(layer "F.Cu")
		(at 87.4522 -97.4598 -90)
		(property "Reference" "R35"
			(at 5.2578 5.87883 90)
			(unlocked yes)
			(layer "F.SilkS")
			(effects
				(font
					(size 0.7874 0.5842)
					(thickness 0.1524)
				)
			)
		)
		(property "Value" "VAL*"
			(at 0.02032 2.13233 270)
			(unlocked yes)
			(layer "F.Fab")
			(hide yes)
			(effects
				(font
					(size 0.7874 0.5842)
					(thickness 0.1524)
				)
			)
		)
		(property "Tolerance" "TOL*"
			(at 0.044704 3.05435 270)
			(unlocked yes)
			(layer "Cmts.User")
			(hide yes)
			(effects
				(font
					(size 0.7874 0.5842)
					(thickness 0.1524)
				)
			)
		)
		(property "User Part Number" "PARTNUM*"
			(at 0.02032 4.024884 270)
			(unlocked yes)
			(layer "Cmts.User")
			(hide yes)
			(effects
				(font
					(size 0.7874 0.5842)
					(thickness 0.1524)
				)
			)
		)
		(property "Device Type" "RESISTOR-G155-11003-01,100KOHMA"
			(at 0.008382 1.210564 270)
			(unlocked yes)
			(layer "F.Fab")
			(hide yes)
			(effects
				(font
					(size 0.7874 0.5842)
					(thickness 0.1524)
				)
			)
		)
		(duplicate_pad_numbers_are_jumpers no)
		(fp_line
			(start -1.143 0.5588)
			(end 1.143 0.5588)
			(stroke
				(width 0.1)
				(type default)
			)
			(layer "F.SilkS")
		)
		(fp_line
			(start 1.143 0.5588)
			(end 1.143 -0.5588)
			(stroke
				(width 0.1)
				(type default)
			)
			(layer "F.SilkS")
		)
		(fp_line
			(start -1.143 -0.5588)
			(end -1.143 0.5588)
			(stroke
				(width 0.1)
				(type default)
			)
			(layer "F.SilkS")
		)
		(fp_line
			(start 1.143 -0.5588)
			(end -1.143 -0.5588)
			(stroke
				(width 0.1)
				(type default)
			)
			(layer "F.SilkS")
		)
		(fp_rect
			(start 1.143 0.5588)
			(end -1.143 -0.5588)
			(stroke
				(width 0)
				(type default)
			)
			(fill no)
			(layer "F.CrtYd")
		)
		(fp_line
			(start -0.508 0.3048)
			(end 0.508 0.3048)
			(stroke
				(width 0.1)
				(type default)
			)
			(layer "F.Fab")
		)
		(fp_line
			(start 0.508 0.3048)
			(end 0.508 -0.3048)
			(stroke
				(width 0.1)
				(type default)
			)
			(layer "F.Fab")
		)
		(fp_line
			(start -0.508 -0.3048)
			(end -0.508 0.3048)
			(stroke
				(width 0.1)
				(type default)
			)
			(layer "F.Fab")
		)
		(fp_line
			(start 0.508 -0.3048)
			(end -0.508 -0.3048)
			(stroke
				(width 0.1)
				(type default)
			)
			(layer "F.Fab")
		)
		(pad "1" smd rect
			(at -0.5334 0 270)
			(size 0.7112 0.6096)
			(layers "F.Cu" "F.Mask" "F.Paste")
			(net "XP3R3V_RT")
		)
		(pad "2" smd rect
			(at 0.5334 0 270)
			(size 0.7112 0.6096)
			(layers "F.Cu" "F.Mask" "F.Paste")
			(net "XP3R3V_AGND")
		)
		(zone
			(layer "F.Cu")
			(hatch none 0.5)
			(connect_pads
				(clearance 0)
			)
			(min_thickness 0.25)
			(keepout
				(tracks allowed)
				(vias not_allowed)
				(pads allowed)
				(copperpour not_allowed)
				(footprints allowed)
			)
			(placement
				(enabled no)
				(sheetname "")
			)
			(fill
				(thermal_gap 0.5)
				(thermal_bridge_width 0.5)
				(island_removal_mode 0)
			)
			(polygon
				(pts
					(xy 87.1474 -97.3836) (xy 87.757 -97.3836) (xy 87.757 -97.536) (xy 87.1474 -97.536)
				)
			)
		)
	)
	(footprint ""
		(layer "F.Cu")
		(at 70.578218 -23.734522)
		(property "Reference" "MAC_PIN6"
			(at 2.667762 2.580132 0)
			(unlocked yes)
			(layer "F.SilkS")
			(effects
				(font
					(size 0.7874 0.5842)
					(thickness 0.1524)
				)
			)
		)
		(property "Value" ""
			(at 0 0 0)
			(layer "F.Fab")
			(effects
				(font
					(size 1.27 1.27)
				)
			)
		)
		(property "Device Type" "NUT-A200-00029-FB"
			(at 0 2.632964 0)
			(unlocked yes)
			(layer "F.Fab")
			(hide yes)
			(effects
				(font
					(size 0.7874 0.5842)
					(thickness 0.1524)
				)
			)
		)
		(property "User Part Number" "PARTNUM*"
			(at 0 3.826764 0)
			(unlocked yes)
			(layer "Cmts.User")
			(hide yes)
			(effects
				(font
					(size 0.7874 0.5842)
					(thickness 0.1524)
				)
			)
		)
		(duplicate_pad_numbers_are_jumpers no)
		(fp_circle
			(center 0 0)
			(end 1.524 0)
			(stroke
				(width 0.1)
				(type default)
			)
			(fill no)
			(layer "F.SilkS")
		)
		(fp_poly
			(pts
				(arc
					(start -1.260856 -0.1524)
					(mid -0.898049 -0.898049)
					(end -0.1524 -1.260856)
				)
				(arc
					(start -0.1524 -0.991616)
					(mid -0.709411 -0.709411)
					(end -0.991616 -0.1524)
				)
			)
			(stroke
				(width 0)
				(type default)
			)
			(fill yes)
			(layer "F.Paste")
		)
		(fp_poly
			(pts
				(arc
					(start -0.1524 1.260856)
					(mid -0.898049 0.898049)
					(end -1.260856 0.1524)
				)
				(arc
					(start -0.991616 0.1524)
					(mid -0.709411 0.709411)
					(end -0.1524 0.991616)
				)
			)
			(stroke
				(width 0)
				(type default)
			)
			(fill yes)
			(layer "F.Paste")
		)
		(fp_poly
			(pts
				(arc
					(start 0.1524 -1.260856)
					(mid 0.898049 -0.898049)
					(end 1.260856 -0.1524)
				)
				(arc
					(start 0.991616 -0.1524)
					(mid 0.709411 -0.709411)
					(end 0.1524 -0.991616)
				)
			)
			(stroke
				(width 0)
				(type default)
			)
			(fill yes)
			(layer "F.Paste")
		)
		(fp_poly
			(pts
				(arc
					(start 1.260856 0.1524)
					(mid 0.898049 0.898049)
					(end 0.1524 1.260856)
				)
				(arc
					(start 0.1524 0.991616)
					(mid 0.709411 0.709411)
					(end 0.991616 0.1524)
				)
			)
			(stroke
				(width 0)
				(type default)
			)
			(fill yes)
			(layer "F.Paste")
		)
		(fp_poly
			(pts
				(arc
					(start 6.35 0)
					(mid -6.35 0)
					(end 6.35 0)
				)
			)
			(stroke
				(width 0)
				(type default)
			)
			(fill no)
			(layer "B.CrtYd")
		)
		(fp_poly
			(pts
				(arc
					(start 1.778 0)
					(mid -1.778 0)
					(end 1.778 0)
				)
			)
			(stroke
				(width 0)
				(type default)
			)
			(fill no)
			(layer "F.CrtYd")
		)
		(fp_circle
			(center 0 0)
			(end 1.1684 0)
			(stroke
				(width 0.1)
				(type default)
			)
			(fill no)
			(layer "F.Fab")
		)
		(pad "1" thru_hole circle
			(at 0 0)
			(size 2.54 2.54)
			(drill 2.0066)
			(layers "*.Cu" "*.Mask")
			(remove_unused_layers no)
			(net "R_MAC_BITEOUT")
			(thermal_gap 0.0254)
			(padstack
				(mode front_inner_back)
				(layer "Inner"
					(shape circle)
					(size 2.54 2.54)
					(clearance 0.0254)
				)
				(layer "B.Cu"
					(shape circle)
					(size 2.54 2.54)
				)
			)
		)
	)
)
